# TIMECARD (Time Appliance Project (Time Card)) — schematic netlist excerpt (pin names and nets, part order shuffled) for the footprints in the layout excerpt that follows; sources: Cadence DE-HDL packaged netlist, KiCad conversion of R4006-B0001-02_R01.brd

R283  RESISTOR  10KOHM 1%  pkg SMC_0402R_H016  page 25 : \1\ = XP3R3V_FPGA ; \2\ = FPGA_IO_2
C277  CAPACITOR  10UF 6.3V 20%  pkg SMC_0402R_H022  page 19 : \1\ = XP1R8V_ICP10100 ; \2\ = SG

(kicad_pcb
	(version 20260206)
	(generator "pcbnew")
	(generator_version "10.0")
	(general
		(thickness 1.6)
		(legacy_teardrops no)
	)
	(paper "A4")
	(title_block
		(title "timecard-production-celestica-r4006 — R4006-B0001-02_R01.brd")
		(comment 1 "Time Appliance Project (Time Card) / footprints 630-631 of 1113")
	)
	(layers
		(0 "F.Cu" signal "TOP")
		(4 "In1.Cu" signal "L02_GND1")
		(6 "In2.Cu" signal "L03_SIG1")
		(8 "In3.Cu" signal "L04_GND2")
		(10 "In4.Cu" signal "L05_VCC1")
		(12 "In5.Cu" signal "L06_VCC2")
		(14 "In6.Cu" signal "L07_GND3")
		(16 "In7.Cu" signal "L08_SIG2")
		(18 "In8.Cu" signal "L09_GND4")
		(2 "B.Cu" signal "BOTTOM")
		(9 "F.Adhes" user "F.Adhesive")
		(11 "B.Adhes" user "B.Adhesive")
		(13 "F.Paste" user "Package Geometry/Pastemask Top")
		(15 "B.Paste" user "Package Geometry/Pastemask Bottom")
		(5 "F.SilkS" user "Ref Des/Silkscreen Top")
		(7 "B.SilkS" user "Ref Des/Silkscreen Bottom")
		(1 "F.Mask" user "Board Geometry/Soldermask Top")
		(3 "B.Mask" user "Board Geometry/Soldermask Bottom")
		(17 "Dwgs.User" user "User.Drawings")
		(19 "Cmts.User" user "User.Comments")
		(21 "Eco1.User" user "User.Eco1")
		(23 "Eco2.User" user "User.Eco2")
		(25 "Edge.Cuts" user "Board Geometry/Outline")
		(27 "Margin" user)
		(31 "F.CrtYd" user "Package Geometry/Place Bound Top")
		(29 "B.CrtYd" user "Package Geometry/Place Bound Bottom")
		(35 "F.Fab" user "Ref Des/Assembly Top")
		(33 "B.Fab" user "Ref Des/Assembly Bottom")
	)
	(footprint ""
		(layer "F.Cu")
		(at 98.044 -64.2874 -90)
		(property "Reference" "R283"
			(at 2.6924 -0.80137 90)
			(unlocked yes)
			(layer "F.SilkS")
			(effects
				(font
					(size 0.7874 0.5842)
					(thickness 0.1524)
				)
			)
		)
		(property "Value" "VAL*"
			(at 0.02032 2.13233 270)
			(unlocked yes)
			(layer "F.Fab")
			(hide yes)
			(effects
				(font
					(size 0.7874 0.5842)
					(thickness 0.1524)
				)
			)
		)
		(property "Tolerance" "TOL*"
			(at 0.044704 3.05435 270)
			(unlocked yes)
			(layer "Cmts.User")
			(hide yes)
			(effects
				(font
					(size 0.7874 0.5842)
					(thickness 0.1524)
				)
			)
		)
		(property "User Part Number" "PARTNUM*"
			(at 0.02032 4.024884 270)
			(unlocked yes)
			(layer "Cmts.User")
			(hide yes)
			(effects
				(font
					(size 0.7874 0.5842)
					(thickness 0.1524)
				)
			)
		)
		(property "Device Type" "RESISTOR-G155-11002-01,10KOHM,A"
			(at 0.008382 1.210564 270)
			(unlocked yes)
			(layer "F.Fab")
			(hide yes)
			(effects
				(font
					(size 0.7874 0.5842)
					(thickness 0.1524)
				)
			)
		)
		(duplicate_pad_numbers_are_jumpers no)
		(fp_line
			(start -1.143 0.5588)
			(end 1.143 0.5588)
			(stroke
				(width 0.1)
				(type default)
			)
			(layer "F.SilkS")
		)
		(fp_line
			(start 1.143 0.5588)
			(end 1.143 -0.5588)
			(stroke
				(width 0.1)
				(type default)
			)
			(layer "F.SilkS")
		)
		(fp_line
			(start -1.143 -0.5588)
			(end -1.143 0.5588)
			(stroke
				(width 0.1)
				(type default)
			)
			(layer "F.SilkS")
		)
		(fp_line
			(start 1.143 -0.5588)
			(end -1.143 -0.5588)
			(stroke
				(width 0.1)
				(type default)
			)
			(layer "F.SilkS")
		)
		(fp_poly
			(pts
				(xy -1.143 0.5588) (xy 1.143 0.5588) (xy 1.143 -0.5588) (xy -1.143 -0.5588)
			)
			(stroke
				(width 0)
				(type default)
			)
			(fill no)
			(layer "F.CrtYd")
		)
		(fp_line
			(start -0.508 0.3048)
			(end 0.508 0.3048)
			(stroke
				(width 0.1)
				(type default)
			)
			(layer "F.Fab")
		)
		(fp_line
			(start 0.508 0.3048)
			(end 0.508 -0.3048)
			(stroke
				(width 0.1)
				(type default)
			)
			(layer "F.Fab")
		)
		(fp_line
			(start -0.508 -0.3048)
			(end -0.508 0.3048)
			(stroke
				(width 0.1)
				(type default)
			)
			(layer "F.Fab")
		)
		(fp_line
			(start 0.508 -0.3048)
			(end -0.508 -0.3048)
			(stroke
				(width 0.1)
				(type default)
			)
			(layer "F.Fab")
		)
		(pad "1" smd rect
			(at -0.5334 0 270)
			(size 0.7112 0.6096)
			(layers "F.Cu" "F.Mask" "F.Paste")
			(net "XP3R3V_FPGA")
		)
		(pad "2" smd rect
			(at 0.5334 0 270)
			(size 0.7112 0.6096)
			(layers "F.Cu" "F.Mask" "F.Paste")
			(net "FPGA_IO_2")
		)
		(zone
			(layer "F.Cu")
			(hatch none 0.5)
			(connect_pads
				(clearance 0)
			)
			(min_thickness 0.25)
			(keepout
				(tracks allowed)
				(vias not_allowed)
				(pads allowed)
				(copperpour not_allowed)
				(footprints allowed)
			)
			(placement
				(enabled no)
				(sheetname "")
			)
			(fill
				(thermal_gap 0.5)
				(thermal_bridge_width 0.5)
				(island_removal_mode 0)
			)
			(polygon
				(pts
					(xy 97.7392 -64.3636) (xy 97.7392 -64.2112) (xy 98.3488 -64.2112) (xy 98.3488 -64.3636)
				)
			)
		)
		(zone
			(layer "F.Cu")
			(hatch none 0.5)
			(connect_pads
				(clearance 0)
			)
			(min_thickness 0.25)
			(keepout
				(tracks not_allowed)
				(vias allowed)
				(pads allowed)
				(copperpour not_allowed)
				(footprints allowed)
			)
			(placement
				(enabled no)
				(sheetname "")
			)
			(fill
				(thermal_gap 0.5)
				(thermal_bridge_width 0.5)
				(island_removal_mode 0)
			)
			(polygon
				(pts
					(xy 97.7392 -64.3636) (xy 97.7392 -64.2112) (xy 98.3488 -64.2112) (xy 98.3488 -64.3636)
				)
			)
		)
	)
	(footprint ""
		(layer "F.Cu")
		(at 23.622 -69.2912)
		(property "Reference" "C277"
			(at 3.302 -0.13843 0)
			(unlocked yes)
			(layer "F.SilkS")
			(effects
				(font
					(size 0.7874 0.5842)
					(thickness 0.1524)
				)
			)
		)
		(property "Value" "VAL*"
			(at 0.0762 2.067306 0)
			(unlocked yes)
			(layer "F.Fab")
			(hide yes)
			(effects
				(font
					(size 0.7874 0.5842)
					(thickness 0.1524)
				)
			)
		)
		(property "Tolerance" "TOL*"
			(at 0.0762 3.032506 0)
			(unlocked yes)
			(layer "Cmts.User")
			(hide yes)
			(effects
				(font
					(size 0.7874 0.5842)
					(thickness 0.1524)
				)
			)
		)
		(property "User Part Number" "PARTNUM*"
			(at 0.1016 4.023106 0)
			(unlocked yes)
			(layer "Cmts.User")
			(hide yes)
			(effects
				(font
					(size 0.7874 0.5842)
					(thickness 0.1524)
				)
			)
		)
		(property "Device Type" "CAPACITOR-G105-0C106-BM,10UF,2A"
			(at 0.0508 1.127506 0)
			(unlocked yes)
			(layer "F.Fab")
			(hide yes)
			(effects
				(font
					(size 0.7874 0.5842)
					(thickness 0.1524)
				)
			)
		)
		(duplicate_pad_numbers_are_jumpers no)
		(fp_line
			(start -1.143 -0.5588)
			(end -1.143 0.5588)
			(stroke
				(width 0.1)
				(type default)
			)
			(layer "F.SilkS")
		)
		(fp_line
			(start -1.143 0.5588)
			(end 1.143 0.5588)
			(stroke
				(width 0.1)
				(type default)
			)
			(layer "F.SilkS")
		)
		(fp_line
			(start 1.143 -0.5588)
			(end -1.143 -0.5588)
			(stroke
				(width 0.1)
				(type default)
			)
			(layer "F.SilkS")
		)
		(fp_line
			(start 1.143 0.5588)
			(end 1.143 -0.5588)
			(stroke
				(width 0.1)
				(type default)
			)
			(layer "F.SilkS")
		)
		(fp_poly
			(pts
				(xy -1.143 -0.5588) (xy -1.143 0.5588) (xy 1.143 0.5588) (xy 1.143 -0.5588)
			)
			(stroke
				(width 0)
				(type default)
			)
			(fill no)
			(layer "F.CrtYd")
		)
		(fp_line
			(start -0.508 -0.3048)
			(end -0.508 0.3048)
			(stroke
				(width 0.1)
				(type default)
			)
			(layer "F.Fab")
		)
		(fp_line
			(start -0.508 0.3048)
			(end 0.508 0.3048)
			(stroke
				(width 0.1)
				(type default)
			)
			(layer "F.Fab")
		)
		(fp_line
			(start 0.508 -0.3048)
			(end -0.508 -0.3048)
			(stroke
				(width 0.1)
				(type default)
			)
			(layer "F.Fab")
		)
		(fp_line
			(start 0.508 0.3048)
			(end 0.508 -0.3048)
			(stroke
				(width 0.1)
				(type default)
			)
			(layer "F.Fab")
		)
		(pad "1" smd rect
			(at -0.5334 0)
			(size 0.7112 0.6096)
			(layers "F.Cu" "F.Mask" "F.Paste")
			(net "XP1R8V_ICP10100")
		)
		(pad "2" smd rect
			(at 0.5334 0)
			(size 0.7112 0.6096)
			(layers "F.Cu" "F.Mask" "F.Paste")
			(net "SG")
		)
		(zone
			(layer "F.Cu")
			(hatch none 0.5)
			(connect_pads
				(clearance 0)
			)
			(min_thickness 0.25)
			(keepout
				(tracks allowed)
				(vias not_allowed)
				(pads allowed)
				(copperpour not_allowed)
				(footprints allowed)
			)
			(placement
				(enabled no)
				(sheetname "")
			)
			(fill
				(thermal_gap 0.5)
				(thermal_bridge_width 0.5)
				(island_removal_mode 0)
			)
			(polygon
				(pts
					(xy 23.5458 -69.596) (xy 23.5458 -68.9864) (xy 23.6982 -68.9864) (xy 23.6982 -69.596)
				)
			)
		)
	)
)
